(kicad_pcb
	(version 20241229)
	(generator "pcbnew")
	(generator_version "9.0")
	(general
		(thickness 1.61)
		(legacy_teardrops no)
	)
	(paper "A3")
	(title_block
		(title "RDIMM DDR5 Tester")
		(date "2026-05-21")
		(rev "2.2.0")
		(company "Antmicro")
		(comment 9 "footprints 12-16 of 796")
	)
	(layers
		(0 "F.Cu" signal)
		(4 "In1.Cu" power)
		(6 "In2.Cu" mixed)
		(8 "In3.Cu" power)
		(10 "In4.Cu" mixed)
		(12 "In5.Cu" power)
		(14 "In6.Cu" mixed)
		(16 "In7.Cu" power)
		(18 "In8.Cu" power)
		(20 "In9.Cu" mixed)
		(22 "In10.Cu" power)
		(2 "B.Cu" signal)
		(9 "F.Adhes" user "F.Adhesive")
		(11 "B.Adhes" user "B.Adhesive")
		(13 "F.Paste" user)
		(15 "B.Paste" user)
		(5 "F.SilkS" user "F.Silkscreen")
		(7 "B.SilkS" user "B.Silkscreen")
		(1 "F.Mask" user)
		(3 "B.Mask" user)
		(17 "Dwgs.User" user "User.Drawings")
		(19 "Cmts.User" user "User.Comments")
		(21 "Eco1.User" user "User.Eco1")
		(23 "Eco2.User" user "User.Eco2")
		(25 "Edge.Cuts" user)
		(27 "Margin" user)
		(31 "F.CrtYd" user "F.Courtyard")
		(29 "B.CrtYd" user "B.Courtyard")
		(35 "F.Fab" user)
		(33 "B.Fab" user)
	)
	(footprint "antmicro-footprints:C_0402_1005Metric"
		(layer "F.Cu")
		(at 140.396843 156.001328 90)
		(descr "Capacitor SMD 0402")
		(tags "capacitor SMD 0402")
		(property "Reference" "C115"
			(at 1.001328 0.403157 90)
			(layer "F.SilkS")
			(effects
				(font
					(size 0.7 0.7)
					(thickness 0.15)
				)
				(justify left bottom)
			)
		)
		(property "Value" "C_100n_0402"
			(at -1.022927 2.155213 90)
			(layer "F.Fab")
			(effects
				(font
					(size 0.7 0.7)
					(thickness 0.15)
				)
				(justify left bottom)
			)
		)
		(property "Datasheet" "https://www.murata.com/products/productdetail?partno=GRM155R61H104KE14%23"
			(at 0 0 90)
			(layer "F.Fab")
			(hide yes)
			(effects
				(font
					(size 1.27 1.27)
					(thickness 0.15)
				)
			)
		)
		(property "Manufacturer" "Murata"
			(at 0 0 90)
			(unlocked yes)
			(layer "F.Fab")
			(hide yes)
			(effects
				(font
					(size 1 1)
					(thickness 0.15)
				)
			)
		)
		(property "MPN" "GRM155R61H104KE14D"
			(at 0 0 90)
			(unlocked yes)
			(layer "F.Fab")
			(hide yes)
			(effects
				(font
					(size 1 1)
					(thickness 0.15)
				)
			)
		)
		(property "Val" "100n"
			(at 0 0 90)
			(unlocked yes)
			(layer "F.Fab")
			(hide yes)
			(effects
				(font
					(size 1 1)
					(thickness 0.15)
				)
			)
		)
		(property "License" "Apache-2.0"
			(at 0 0 90)
			(unlocked yes)
			(layer "F.Fab")
			(hide yes)
			(effects
				(font
					(size 1 1)
					(thickness 0.15)
				)
			)
		)
		(property "Author" "Antmicro"
			(at 0 0 90)
			(unlocked yes)
			(layer "F.Fab")
			(hide yes)
			(effects
				(font
					(size 1 1)
					(thickness 0.15)
				)
			)
		)
		(property "Voltage" "50V"
			(at 0 0 90)
			(unlocked yes)
			(layer "F.Fab")
			(hide yes)
			(effects
				(font
					(size 1 1)
					(thickness 0.15)
				)
			)
		)
		(property "Dielectric" "X5R"
			(at 0 0 90)
			(unlocked yes)
			(layer "F.Fab")
			(hide yes)
			(effects
				(font
					(size 1 1)
					(thickness 0.15)
				)
			)
		)
		(sheetname "/Debug FTDI + VNA/")
		(sheetfile "debug-ftdi.kicad_sch")
		(attr smd)
		(fp_rect
			(start -0.925 -0.47)
			(end 0.925 0.47)
			(stroke
				(width 0.05)
				(type default)
			)
			(fill no)
			(layer "F.CrtYd")
		)
		(fp_line
			(start 0.504 -0.25)
			(end 0.504 0.248)
			(stroke
				(width 0.15)
				(type solid)
			)
			(layer "F.Fab")
		)
		(fp_line
			(start -0.494 -0.25)
			(end 0.504 -0.25)
			(stroke
				(width 0.15)
				(type solid)
			)
			(layer "F.Fab")
		)
		(fp_line
			(start 0.504 0.248)
			(end -0.494 0.248)
			(stroke
				(width 0.15)
				(type solid)
			)
			(layer "F.Fab")
		)
		(fp_line
			(start -0.494 0.248)
			(end -0.494 -0.25)
			(stroke
				(width 0.15)
				(type solid)
			)
			(layer "F.Fab")
		)
		(fp_text user "Author: Antmicro"
			(at -0.939 3.399 90)
			(layer "F.Fab")
			(effects
				(font
					(size 0.7 0.7)
					(thickness 0.15)
				)
				(justify left bottom)
			)
		)
		(fp_text user "${REFERENCE}"
			(at -0.939 4.599 90)
			(layer "F.Fab")
			(effects
				(font
					(size 0.7 0.7)
					(thickness 0.15)
				)
				(justify left bottom)
			)
		)
		(fp_text user "License: Apache-2.0"
			(at -0.939 5.799 90)
			(layer "F.Fab")
			(effects
				(font
					(size 0.7 0.7)
					(thickness 0.15)
				)
				(justify left bottom)
			)
		)
		(pad "1" smd roundrect
			(at -0.48 0 90)
			(size 0.59 0.64)
			(layers "F.Cu" "F.Mask" "F.Paste")
			(roundrect_rratio 0.25)
			(net 6 "/Debug FTDI + VNA/FTDI_3V3")
			(pintype "passive")
		)
		(pad "2" smd roundrect
			(at 0.48 0 90)
			(size 0.59 0.64)
			(layers "F.Cu" "F.Mask" "F.Paste")
			(roundrect_rratio 0.25)
			(net 1 "GND")
			(pintype "passive")
		)
	)
	(footprint "antmicro-footprints:C_0402_1005Metric"
		(layer "F.Cu")
		(at 137.184328 155.996157 90)
		(descr "Capacitor SMD 0402")
		(tags "capacitor SMD 0402")
		(property "Reference" "C111"
			(at 1.296157 0.765672 90)
			(layer "F.SilkS")
			(effects
				(font
					(size 0.7 0.7)
					(thickness 0.15)
				)
				(justify left bottom)
			)
		)
		(property "Value" "C_18p_0402"
			(at -1.022927 2.155213 90)
			(layer "F.Fab")
			(effects
				(font
					(size 0.7 0.7)
					(thickness 0.15)
				)
				(justify left bottom)
			)
		)
		(property "Datasheet" "https://product.samsungsem.com/mlcc/CL05C180JB51PN.do"
			(at 0 0 90)
			(layer "F.Fab")
			(hide yes)
			(effects
				(font
					(size 1.27 1.27)
					(thickness 0.15)
				)
			)
		)
		(property "Manufacturer" "Samsung Electro-Mechanics"
			(at 0 0 90)
			(unlocked yes)
			(layer "F.Fab")
			(hide yes)
			(effects
				(font
					(size 1 1)
					(thickness 0.15)
				)
			)
		)
		(property "MPN" "CL05C180JB51PNC"
			(at 0 0 90)
			(unlocked yes)
			(layer "F.Fab")
			(hide yes)
			(effects
				(font
					(size 1 1)
					(thickness 0.15)
				)
			)
		)
		(property "Val" "18p"
			(at 0 0 90)
			(unlocked yes)
			(layer "F.Fab")
			(hide yes)
			(effects
				(font
					(size 1 1)
					(thickness 0.15)
				)
			)
		)
		(property "License" "Apache-2.0"
			(at 0 0 90)
			(unlocked yes)
			(layer "F.Fab")
			(hide yes)
			(effects
				(font
					(size 1 1)
					(thickness 0.15)
				)
			)
		)
		(property "Author" "Antmicro"
			(at 0 0 90)
			(unlocked yes)
			(layer "F.Fab")
			(hide yes)
			(effects
				(font
					(size 1 1)
					(thickness 0.15)
				)
			)
		)
		(property "Voltage" ""
			(at 0 0 90)
			(unlocked yes)
			(layer "F.Fab")
			(hide yes)
			(effects
				(font
					(size 1 1)
					(thickness 0.15)
				)
			)
		)
		(property "Dielectric" ""
			(at 0 0 90)
			(unlocked yes)
			(layer "F.Fab")
			(hide yes)
			(effects
				(font
					(size 1 1)
					(thickness 0.15)
				)
			)
		)
		(sheetname "/Debug FTDI + VNA/")
		(sheetfile "debug-ftdi.kicad_sch")
		(attr smd)
		(fp_rect
			(start -0.925 -0.47)
			(end 0.925 0.47)
			(stroke
				(width 0.05)
				(type default)
			)
			(fill no)
			(layer "F.CrtYd")
		)
		(fp_line
			(start 0.504 -0.25)
			(end 0.504 0.248)
			(stroke
				(width 0.15)
				(type solid)
			)
			(layer "F.Fab")
		)
		(fp_line
			(start -0.494 -0.25)
			(end 0.504 -0.25)
			(stroke
				(width 0.15)
				(type solid)
			)
			(layer "F.Fab")
		)
		(fp_line
			(start 0.504 0.248)
			(end -0.494 0.248)
			(stroke
				(width 0.15)
				(type solid)
			)
			(layer "F.Fab")
		)
		(fp_line
			(start -0.494 0.248)
			(end -0.494 -0.25)
			(stroke
				(width 0.15)
				(type solid)
			)
			(layer "F.Fab")
		)
		(fp_text user "Author: Antmicro"
			(at -0.939 3.399 90)
			(layer "F.Fab")
			(effects
				(font
					(size 0.7 0.7)
					(thickness 0.15)
				)
				(justify left bottom)
			)
		)
		(fp_text user "License: Apache-2.0"
			(at -0.939 5.799 90)
			(layer "F.Fab")
			(effects
				(font
					(size 0.7 0.7)
					(thickness 0.15)
				)
				(justify left bottom)
			)
		)
		(fp_text user "${REFERENCE}"
			(at -0.939 4.599 90)
			(layer "F.Fab")
			(effects
				(font
					(size 0.7 0.7)
					(thickness 0.15)
				)
				(justify left bottom)
			)
		)
		(pad "1" smd roundrect
			(at -0.48 0 90)
			(size 0.59 0.64)
			(layers "F.Cu" "F.Mask" "F.Paste")
			(roundrect_rratio 0.25)
			(net 4 "/Debug FTDI + VNA/FTDI_XI")
			(pintype "passive")
		)
		(pad "2" smd roundrect
			(at 0.48 0 90)
			(size 0.59 0.64)
			(layers "F.Cu" "F.Mask" "F.Paste")
			(roundrect_rratio 0.25)
			(net 1 "GND")
			(pintype "passive")
		)
	)
	(footprint "antmicro-footprints:C_0402_1005Metric"
		(layer "F.Cu")
		(at 141.024499 169.049 -90)
		(descr "Capacitor SMD 0402")
		(tags "capacitor SMD 0402")
		(property "Reference" "C119"
			(at -1.099 -2.225501 90)
			(layer "F.SilkS")
			(effects
				(font
					(size 0.7 0.7)
					(thickness 0.15)
				)
				(justify right bottom)
			)
		)
		(property "Value" "C_100n_0402"
			(at -1.022927 2.155213 90)
			(layer "F.Fab")
			(effects
				(font
					(size 0.7 0.7)
					(thickness 0.15)
				)
				(justify right bottom)
			)
		)
		(property "Datasheet" "https://www.murata.com/products/productdetail?partno=GRM155R61H104KE14%23"
			(at 0 0 270)
			(layer "F.Fab")
			(hide yes)
			(effects
				(font
					(size 1.27 1.27)
					(thickness 0.15)
				)
			)
		)
		(property "Manufacturer" "Murata"
			(at 0 0 270)
			(unlocked yes)
			(layer "F.Fab")
			(hide yes)
			(effects
				(font
					(size 1 1)
					(thickness 0.15)
				)
			)
		)
		(property "MPN" "GRM155R61H104KE14D"
			(at 0 0 270)
			(unlocked yes)
			(layer "F.Fab")
			(hide yes)
			(effects
				(font
					(size 1 1)
					(thickness 0.15)
				)
			)
		)
		(property "Val" "100n"
			(at 0 0 270)
			(unlocked yes)
			(layer "F.Fab")
			(hide yes)
			(effects
				(font
					(size 1 1)
					(thickness 0.15)
				)
			)
		)
		(property "License" "Apache-2.0"
			(at 0 0 270)
			(unlocked yes)
			(layer "F.Fab")
			(hide yes)
			(effects
				(font
					(size 1 1)
					(thickness 0.15)
				)
			)
		)
		(property "Author" "Antmicro"
			(at 0 0 270)
			(unlocked yes)
			(layer "F.Fab")
			(hide yes)
			(effects
				(font
					(size 1 1)
					(thickness 0.15)
				)
			)
		)
		(property "Voltage" "50V"
			(at 0 0 270)
			(unlocked yes)
			(layer "F.Fab")
			(hide yes)
			(effects
				(font
					(size 1 1)
					(thickness 0.15)
				)
			)
		)
		(property "Dielectric" "X5R"
			(at 0 0 270)
			(unlocked yes)
			(layer "F.Fab")
			(hide yes)
			(effects
				(font
					(size 1 1)
					(thickness 0.15)
				)
			)
		)
		(sheetname "/Debug FTDI + VNA/")
		(sheetfile "debug-ftdi.kicad_sch")
		(attr smd)
		(fp_rect
			(start -0.925 -0.47)
			(end 0.925 0.47)
			(stroke
				(width 0.05)
				(type default)
			)
			(fill no)
			(layer "F.CrtYd")
		)
		(fp_line
			(start -0.494 0.248)
			(end -0.494 -0.25)
			(stroke
				(width 0.15)
				(type solid)
			)
			(layer "F.Fab")
		)
		(fp_line
			(start 0.504 0.248)
			(end -0.494 0.248)
			(stroke
				(width 0.15)
				(type solid)
			)
			(layer "F.Fab")
		)
		(fp_line
			(start -0.494 -0.25)
			(end 0.504 -0.25)
			(stroke
				(width 0.15)
				(type solid)
			)
			(layer "F.Fab")
		)
		(fp_line
			(start 0.504 -0.25)
			(end 0.504 0.248)
			(stroke
				(width 0.15)
				(type solid)
			)
			(layer "F.Fab")
		)
		(fp_text user "Author: Antmicro"
			(at -0.939 3.399 270)
			(layer "F.Fab")
			(effects
				(font
					(size 0.7 0.7)
					(thickness 0.15)
				)
				(justify left bottom)
			)
		)
		(fp_text user "License: Apache-2.0"
			(at -0.939 5.799 270)
			(layer "F.Fab")
			(effects
				(font
					(size 0.7 0.7)
					(thickness 0.15)
				)
				(justify left bottom)
			)
		)
		(fp_text user "${REFERENCE}"
			(at -0.939 4.599 270)
			(layer "F.Fab")
			(effects
				(font
					(size 0.7 0.7)
					(thickness 0.15)
				)
				(justify left bottom)
			)
		)
		(pad "1" smd roundrect
			(at -0.48 0 270)
			(size 0.59 0.64)
			(layers "F.Cu" "F.Mask" "F.Paste")
			(roundrect_rratio 0.25)
			(net 6 "/Debug FTDI + VNA/FTDI_3V3")
			(pintype "passive")
		)
		(pad "2" smd roundrect
			(at 0.48 0 270)
			(size 0.59 0.64)
			(layers "F.Cu" "F.Mask" "F.Paste")
			(roundrect_rratio 0.25)
			(net 1 "GND")
			(pintype "passive")
		)
	)
	(footprint "antmicro-footprints:C_0402_1005Metric"
		(layer "F.Cu")
		(at 148.591843 165.716328)
		(descr "Capacitor SMD 0402")
		(tags "capacitor SMD 0402")
		(property "Reference" "C122"
			(at 0.928157 0.413672 0)
			(layer "F.SilkS")
			(effects
				(font
					(size 0.7 0.7)
					(thickness 0.15)
				)
				(justify left bottom)
			)
		)
		(property "Value" "C_4u7_0402"
			(at -1.022927 2.155213 0)
			(layer "F.Fab")
			(effects
				(font
					(size 0.7 0.7)
					(thickness 0.15)
				)
				(justify left bottom)
			)
		)
		(property "Datasheet" "https://www.murata.com/products/productdetail?partno=GRM155R61A475MEAA%23"
			(at 0 0 0)
			(layer "F.Fab")
			(hide yes)
			(effects
				(font
					(size 1.27 1.27)
					(thickness 0.15)
				)
			)
		)
		(property "Manufacturer" "Murata"
			(at 0 0 0)
			(unlocked yes)
			(layer "F.Fab")
			(hide yes)
			(effects
				(font
					(size 1 1)
					(thickness 0.15)
				)
			)
		)
		(property "MPN" "GRM155R61A475MEAAD"
			(at 0 0 0)
			(unlocked yes)
			(layer "F.Fab")
			(hide yes)
			(effects
				(font
					(size 1 1)
					(thickness 0.15)
				)
			)
		)
		(property "Val" "4u7"
			(at 0 0 0)
			(unlocked yes)
			(layer "F.Fab")
			(hide yes)
			(effects
				(font
					(size 1 1)
					(thickness 0.15)
				)
			)
		)
		(property "License" "Apache-2.0"
			(at 0 0 0)
			(unlocked yes)
			(layer "F.Fab")
			(hide yes)
			(effects
				(font
					(size 1 1)
					(thickness 0.15)
				)
			)
		)
		(property "Author" "Antmicro"
			(at 0 0 0)
			(unlocked yes)
			(layer "F.Fab")
			(hide yes)
			(effects
				(font
					(size 1 1)
					(thickness 0.15)
				)
			)
		)
		(property "Voltage" ""
			(at 0 0 0)
			(unlocked yes)
			(layer "F.Fab")
			(hide yes)
			(effects
				(font
					(size 1 1)
					(thickness 0.15)
				)
			)
		)
		(property "Dielectric" ""
			(at 0 0 0)
			(unlocked yes)
			(layer "F.Fab")
			(hide yes)
			(effects
				(font
					(size 1 1)
					(thickness 0.15)
				)
			)
		)
		(sheetname "/Debug FTDI + VNA/")
		(sheetfile "debug-ftdi.kicad_sch")
		(attr smd)
		(fp_rect
			(start -0.925 -0.47)
			(end 0.925 0.47)
			(stroke
				(width 0.05)
				(type default)
			)
			(fill no)
			(layer "F.CrtYd")
		)
		(fp_line
			(start -0.494 -0.25)
			(end 0.504 -0.25)
			(stroke
				(width 0.15)
				(type solid)
			)
			(layer "F.Fab")
		)
		(fp_line
			(start -0.494 0.248)
			(end -0.494 -0.25)
			(stroke
				(width 0.15)
				(type solid)
			)
			(layer "F.Fab")
		)
		(fp_line
			(start 0.504 -0.25)
			(end 0.504 0.248)
			(stroke
				(width 0.15)
				(type solid)
			)
			(layer "F.Fab")
		)
		(fp_line
			(start 0.504 0.248)
			(end -0.494 0.248)
			(stroke
				(width 0.15)
				(type solid)
			)
			(layer "F.Fab")
		)
		(fp_text user "${REFERENCE}"
			(at -0.939 4.599 0)
			(layer "F.Fab")
			(effects
				(font
					(size 0.7 0.7)
					(thickness 0.15)
				)
				(justify left bottom)
			)
		)
		(fp_text user "License: Apache-2.0"
			(at -0.939 5.799 0)
			(layer "F.Fab")
			(effects
				(font
					(size 0.7 0.7)
					(thickness 0.15)
				)
				(justify left bottom)
			)
		)
		(fp_text user "Author: Antmicro"
			(at -0.939 3.399 0)
			(layer "F.Fab")
			(effects
				(font
					(size 0.7 0.7)
					(thickness 0.15)
				)
				(justify left bottom)
			)
		)
		(pad "1" smd roundrect
			(at -0.48 0)
			(size 0.59 0.64)
			(layers "F.Cu" "F.Mask" "F.Paste")
			(roundrect_rratio 0.25)
			(net 34 "/Debug FTDI + VNA/FTDI_VCORE")
			(pintype "passive")
		)
		(pad "2" smd roundrect
			(at 0.48 0)
			(size 0.59 0.64)
			(layers "F.Cu" "F.Mask" "F.Paste")
			(roundrect_rratio 0.25)
			(net 1 "GND")
			(pintype "passive")
		)
	)
	(footprint "antmicro-footprints:FB_0603_1608Metric"
		(layer "F.Cu")
		(at 132.435 159.484 -90)
		(property "Reference" "FB2"
			(at -0.584 0.935 90)
			(layer "F.SilkS")
			(effects
				(font
					(size 0.7 0.7)
					(thickness 0.15)
				)
				(justify right bottom)
			)
		)
		(property "Value" "FB_600Z_0.5A_Murata-BLM18AG_0603"
			(at 0 1.5 90)
			(layer "F.Fab")
			(effects
				(font
					(size 0.7 0.7)
					(thickness 0.15)
				)
				(justify right bottom)
			)
		)
		(property "Datasheet" "https://www.murata.com/en-us/products/productdata/8796738650142/ENFA0003.pdf"
			(at 0 0 270)
			(layer "F.Fab")
			(hide yes)
			(effects
				(font
					(size 1.27 1.27)
					(thickness 0.15)
				)
			)
		)
		(property "Val" "600Z/0.5A"
			(at 0 0 270)
			(unlocked yes)
			(layer "F.Fab")
			(hide yes)
			(effects
				(font
					(size 1 1)
					(thickness 0.15)
				)
			)
		)
		(property "MPN" "BLM18AG601SN1D"
			(at 0 0 270)
			(unlocked yes)
			(layer "F.Fab")
			(hide yes)
			(effects
				(font
					(size 1 1)
					(thickness 0.15)
				)
			)
		)
		(property "Manufacturer" "Murata"
			(at 0 0 270)
			(unlocked yes)
			(layer "F.Fab")
			(hide yes)
			(effects
				(font
					(size 1 1)
					(thickness 0.15)
				)
			)
		)
		(property "Author" "Antmicro"
			(at 0 0 270)
			(unlocked yes)
			(layer "F.Fab")
			(hide yes)
			(effects
				(font
					(size 1 1)
					(thickness 0.15)
				)
			)
		)
		(property "License" "Apache-2.0"
			(at 0 0 270)
			(unlocked yes)
			(layer "F.Fab")
			(hide yes)
			(effects
				(font
					(size 1 1)
					(thickness 0.15)
				)
			)
		)
		(sheetname "/Debug FTDI + VNA/")
		(sheetfile "debug-ftdi.kicad_sch")
		(attr smd)
		(fp_line
			(start -0.15 0.4)
			(end 0.15 0.4)
			(stroke
				(width 0.15)
				(type solid)
			)
			(layer "F.SilkS")
		)
		(fp_line
			(start -0.15 -0.4)
			(end 0.15 -0.4)
			(stroke
				(width 0.15)
				(type solid)
			)
			(layer "F.SilkS")
		)
		(fp_rect
			(start -1.25 -0.65)
			(end 1.25 0.65)
			(stroke
				(width 0.05)
				(type solid)
			)
			(fill no)
			(layer "F.CrtYd")
		)
		(fp_line
			(start -0.803 0.406)
			(end -0.803 -0.408)
			(stroke
				(width 0.15)
				(type solid)
			)
			(layer "F.Fab")
		)
		(fp_line
			(start 0.8 0.406)
			(end -0.803 0.406)
			(stroke
				(width 0.15)
				(type solid)
			)
			(layer "F.Fab")
		)
		(fp_line
			(start 0.8 -0.408)
			(end 0.8 0.406)
			(stroke
				(width 0.15)
				(type solid)
			)
			(layer "F.Fab")
		)
		(fp_line
			(start 0.8 -0.408)
			(end -0.803 -0.408)
			(stroke
				(width 0.15)
				(type solid)
			)
			(layer "F.Fab")
		)
		(fp_text user "Author: Antmicro"
			(at -1.653 3.162 270)
			(layer "F.Fab")
			(effects
				(font
					(size 0.7 0.7)
					(thickness 0.15)
				)
				(justify left bottom)
			)
		)
		(fp_text user "${REFERENCE}"
			(at -1.653 4.6 270)
			(layer "F.Fab")
			(effects
				(font
					(size 0.7 0.7)
					(thickness 0.15)
				)
				(justify left bottom)
			)
		)
		(fp_text user "License: Apache-2.0"
			(at -1.653 5.9 270)
			(layer "F.Fab")
			(effects
				(font
					(size 0.7 0.7)
					(thickness 0.15)
				)
				(justify left bottom)
			)
		)
		(pad "1" smd roundrect
			(at -0.7 0 270)
			(size 0.8 1)
			(layers "F.Cu" "F.Mask" "F.Paste")
			(roundrect_rratio 0.2)
			(net 6 "/Debug FTDI + VNA/FTDI_3V3")
			(pintype "passive")
		)
		(pad "2" smd roundrect
			(at 0.7 0 270)
			(size 0.8 1)
			(layers "F.Cu" "F.Mask" "F.Paste")
			(roundrect_rratio 0.2)
			(net 5 "/Debug FTDI + VNA/FTDI_VPHY")
			(pintype "passive")
		)
	)
)
